# T6G (Grand Teton) — schematic netlist excerpt (pin names and nets, part order shuffled) for the footprints in the layout excerpt that follows; sources: Cadence DE-HDL packaged netlist, KiCad conversion of 04192023_DAF0TMB3IC0_F0TG_MB_C_brd_V02_OCP.brd

R639  Q_RES  1K 1% CHIP  pkg 0402LF  page 83 : A = CPLD_PROGRAMN ; B = P3V3_AUX

Y8004  Q_XTAL_4P_13BI_24GND  12MHZ MISC  pkg X_4S_8Z25000020_2-5X2  page 234
  X1  = USB_HUB_XTAL_IN
  G1  = GND
  X2  = USB_HUB_XTAL_OUT
  G2  = GND

(kicad_pcb
	(version 20260206)
	(generator "pcbnew")
	(generator_version "10.0")
	(general
		(thickness 1.6)
		(legacy_teardrops no)
	)
	(paper "A4")
	(title_block
		(title "04192023_DAF0TMB3IC0_F0TG_MB_C_brd_V02_OCP.brd")
		(comment 1 "Grand Teton / footprints 1722-1723 of 8354")
	)
	(layers
		(0 "F.Cu" signal "TOP")
		(4 "In1.Cu" signal "GND")
		(6 "In2.Cu" signal "IN1")
		(8 "In3.Cu" signal "GND1")
		(10 "In4.Cu" signal "IN2")
		(12 "In5.Cu" signal "GND2")
		(14 "In6.Cu" signal "IN3")
		(16 "In7.Cu" signal "GND3")
		(18 "In8.Cu" signal "VCC")
		(20 "In9.Cu" signal "VCC1")
		(22 "In10.Cu" signal "GND4")
		(24 "In11.Cu" signal "IN4")
		(26 "In12.Cu" signal "GND5")
		(28 "In13.Cu" signal "IN5")
		(30 "In14.Cu" signal "GND6")
		(32 "In15.Cu" signal "IN6")
		(34 "In16.Cu" signal "GND7")
		(2 "B.Cu" signal "BOTTOM")
		(9 "F.Adhes" user "F.Adhesive")
		(11 "B.Adhes" user "B.Adhesive")
		(13 "F.Paste" user "Package Geometry/Pastemask Top")
		(15 "B.Paste" user "Package Geometry/Pastemask Bottom")
		(5 "F.SilkS" user "Ref Des/Silkscreen Top")
		(7 "B.SilkS" user "Ref Des/Silkscreen Bottom")
		(1 "F.Mask" user "Board Geometry/Soldermask Top")
		(3 "B.Mask" user "Board Geometry/Soldermask Bottom")
		(17 "Dwgs.User" user "User.Drawings")
		(19 "Cmts.User" user "User.Comments")
		(21 "Eco1.User" user "User.Eco1")
		(23 "Eco2.User" user "User.Eco2")
		(25 "Edge.Cuts" user "Board Geometry/Outline")
		(27 "Margin" user)
		(31 "F.CrtYd" user "Package Geometry/Place Bound Top")
		(29 "B.CrtYd" user "Package Geometry/Place Bound Bottom")
		(35 "F.Fab" user "Ref Des/Assembly Top")
		(33 "B.Fab" user "Ref Des/Assembly Bottom")
	)
	(footprint ""
		(layer "F.Cu")
		(at 167.132 -120.360948 180)
		(property "Reference" "R639"
			(at 0 0 180)
			(layer "F.SilkS")
			(hide yes)
			(effects
				(font
					(size 1.27 1.27)
				)
			)
		)
		(property "Value" ""
			(at 0 0 180)
			(layer "F.Fab")
			(effects
				(font
					(size 1.27 1.27)
				)
			)
		)
		(duplicate_pad_numbers_are_jumpers no)
		(fp_line
			(start 0.7874 0.4064)
			(end -0.7874 0.4064)
			(stroke
				(width 0.1524)
				(type default)
			)
			(layer "F.SilkS")
		)
		(fp_line
			(start 0.7874 -0.4064)
			(end 0.7874 0.4064)
			(stroke
				(width 0.1524)
				(type default)
			)
			(layer "F.SilkS")
		)
		(fp_line
			(start -0.7874 0.4064)
			(end -0.7874 -0.4064)
			(stroke
				(width 0.1524)
				(type default)
			)
			(layer "F.SilkS")
		)
		(fp_line
			(start -0.7874 -0.4064)
			(end 0.7874 -0.4064)
			(stroke
				(width 0.1524)
				(type default)
			)
			(layer "F.SilkS")
		)
		(fp_line
			(start 0.67945 0.3048)
			(end 0.120396 0.3048)
			(stroke
				(width 0.1)
				(type default)
			)
			(layer "F.Fab")
		)
		(fp_line
			(start 0.67945 -0.3048)
			(end 0.67945 0.3048)
			(stroke
				(width 0.1)
				(type default)
			)
			(layer "F.Fab")
		)
		(fp_line
			(start 0.12065 -0.2794)
			(end 0.12065 -0.3048)
			(stroke
				(width 0.1)
				(type default)
			)
			(layer "F.Fab")
		)
		(fp_line
			(start 0.12065 -0.3048)
			(end 0.67945 -0.3048)
			(stroke
				(width 0.1)
				(type default)
			)
			(layer "F.Fab")
		)
		(fp_line
			(start 0.120396 0.3048)
			(end 0.120396 0.2794)
			(stroke
				(width 0.1)
				(type default)
			)
			(layer "F.Fab")
		)
		(fp_line
			(start 0.120396 0.2794)
			(end -0.12065 0.2794)
			(stroke
				(width 0.1)
				(type default)
			)
			(layer "F.Fab")
		)
		(fp_line
			(start -0.12065 0.3048)
			(end -0.67945 0.3048)
			(stroke
				(width 0.1)
				(type default)
			)
			(layer "F.Fab")
		)
		(fp_line
			(start -0.12065 0.2794)
			(end -0.12065 0.3048)
			(stroke
				(width 0.1)
				(type default)
			)
			(layer "F.Fab")
		)
		(fp_line
			(start -0.12065 -0.2794)
			(end 0.12065 -0.2794)
			(stroke
				(width 0.1)
				(type default)
			)
			(layer "F.Fab")
		)
		(fp_line
			(start -0.12065 -0.305054)
			(end -0.12065 -0.2794)
			(stroke
				(width 0.1)
				(type default)
			)
			(layer "F.Fab")
		)
		(fp_line
			(start -0.67945 0.3048)
			(end -0.67945 -0.305054)
			(stroke
				(width 0.1)
				(type default)
			)
			(layer "F.Fab")
		)
		(fp_line
			(start -0.67945 -0.305054)
			(end -0.12065 -0.305054)
			(stroke
				(width 0.1)
				(type default)
			)
			(layer "F.Fab")
		)
		(pad "1" smd circle
			(at -0.40005 0 180)
			(size 0 0)
			(layers "F.Cu" "F.Mask" "F.Paste")
			(net "CPLD_PROGRAMN")
		)
		(pad "2" smd circle
			(at 0.40005 0 180)
			(size 0 0)
			(layers "F.Cu" "F.Mask" "F.Paste")
			(net "P3V3_AUX")
		)
	)
	(footprint ""
		(layer "F.Cu")
		(at 7.124192 -99.42195)
		(property "Reference" "Y8004"
			(at -2.821178 -3.284728 0)
			(unlocked yes)
			(layer "F.SilkS")
			(effects
				(font
					(size 0.7874 0.5842)
					(thickness 0.1524)
				)
				(justify left)
			)
		)
		(property "Value" ""
			(at 0 0 0)
			(layer "F.Fab")
			(effects
				(font
					(size 1.27 1.27)
				)
			)
		)
		(duplicate_pad_numbers_are_jumpers no)
		(fp_line
			(start -1.380236 -1.579372)
			(end -1.380236 1.579372)
			(stroke
				(width 0.1524)
				(type default)
			)
			(layer "F.SilkS")
		)
		(fp_line
			(start -1.380236 1.579372)
			(end 1.380236 1.579372)
			(stroke
				(width 0.1524)
				(type default)
			)
			(layer "F.SilkS")
		)
		(fp_line
			(start 1.380236 -1.579372)
			(end -1.380236 -1.579372)
			(stroke
				(width 0.1524)
				(type default)
			)
			(layer "F.SilkS")
		)
		(fp_line
			(start 1.380236 1.579372)
			(end 1.380236 -1.579372)
			(stroke
				(width 0.1524)
				(type default)
			)
			(layer "F.SilkS")
		)
		(fp_poly
			(pts
				(xy -2.914396 -1.099312) (xy -2.914396 -0.337312) (xy -2.152396 -0.718312)
			)
			(stroke
				(width 0)
				(type default)
			)
			(fill yes)
			(layer "F.SilkS")
		)
		(fp_line
			(start -1.050036 -1.299972)
			(end -1.050036 1.299972)
			(stroke
				(width 0.1)
				(type default)
			)
			(layer "F.Fab")
		)
		(fp_line
			(start -1.050036 1.299972)
			(end 1.050036 1.299972)
			(stroke
				(width 0.1)
				(type default)
			)
			(layer "F.Fab")
		)
		(fp_line
			(start 1.050036 -1.299972)
			(end -1.050036 -1.299972)
			(stroke
				(width 0.1)
				(type default)
			)
			(layer "F.Fab")
		)
		(fp_line
			(start 1.050036 1.299972)
			(end 1.050036 -1.299972)
			(stroke
				(width 0.1)
				(type default)
			)
			(layer "F.Fab")
		)
		(fp_poly
			(pts
				(xy -2.3114 -1.306068) (xy -2.3114 -0.544068) (xy -1.5494 -0.925068)
			)
			(stroke
				(width 0)
				(type default)
			)
			(fill yes)
			(layer "F.Fab")
		)
		(pad "1" smd rect
			(at -0.774954 -0.925068)
			(size 0.9144 1.016)
			(layers "F.Cu" "F.Mask" "F.Paste")
			(net "USB_HUB_XTAL_IN")
		)
		(pad "2" smd rect
			(at -0.774954 0.925068)
			(size 0.9144 1.016)
			(layers "F.Cu" "F.Mask" "F.Paste")
			(net "GND")
		)
		(pad "3" smd rect
			(at 0.774954 0.925068)
			(size 0.9144 1.016)
			(layers "F.Cu" "F.Mask" "F.Paste")
			(net "USB_HUB_XTAL_OUT")
		)
		(pad "4" smd rect
			(at 0.774954 -0.925068)
			(size 0.9144 1.016)
			(layers "F.Cu" "F.Mask" "F.Paste")
			(net "GND")
		)
	)
)
